FILE_TYPE=LIBRARY_PARTS;
primitive 'CONN14_210HP207GBR1';
  pin
    '1':
      PIN_NUMBER='(1)';
      BIDIRECTIONAL='TRUE';
      INPUT_LOAD='(-0.01,0.01)';
      OUTPUT_LOAD='(1.0,-1.0)';
    '2':
      PIN_NUMBER='(2)';
      BIDIRECTIONAL='TRUE';
      INPUT_LOAD='(-0.01,0.01)';
      OUTPUT_LOAD='(1.0,-1.0)';
    '3':
      PIN_NUMBER='(3)';
      BIDIRECTIONAL='TRUE';
      INPUT_LOAD='(-0.01,0.01)';
      OUTPUT_LOAD='(1.0,-1.0)';
    '4':
      PIN_NUMBER='(4)';
      BIDIRECTIONAL='TRUE';
      INPUT_LOAD='(-0.01,0.01)';
      OUTPUT_LOAD='(1.0,-1.0)';
    '5':
      PIN_NUMBER='(5)';
      BIDIRECTIONAL='TRUE';
      INPUT_LOAD='(-0.01,0.01)';
      OUTPUT_LOAD='(1.0,-1.0)';
    '6':
      PIN_NUMBER='(6)';
      BIDIRECTIONAL='TRUE';
      INPUT_LOAD='(-0.01,0.01)';
      OUTPUT_LOAD='(1.0,-1.0)';
    '7':
      PIN_NUMBER='(7)';
      BIDIRECTIONAL='TRUE';
      INPUT_LOAD='(-0.01,0.01)';
      OUTPUT_LOAD='(1.0,-1.0)';
    '8':
      PIN_NUMBER='(8)';
      BIDIRECTIONAL='TRUE';
      INPUT_LOAD='(-0.01,0.01)';
      OUTPUT_LOAD='(1.0,-1.0)';
    '9':
      PIN_NUMBER='(9)';
      BIDIRECTIONAL='TRUE';
      INPUT_LOAD='(-0.01,0.01)';
      OUTPUT_LOAD='(1.0,-1.0)';
    '10':
      PIN_NUMBER='(10)';
      BIDIRECTIONAL='TRUE';
      INPUT_LOAD='(-0.01,0.01)';
      OUTPUT_LOAD='(1.0,-1.0)';
    '11':
      PIN_NUMBER='(11)';
      BIDIRECTIONAL='TRUE';
      INPUT_LOAD='(-0.01,0.01)';
      OUTPUT_LOAD='(1.0,-1.0)';
    '12':
      PIN_NUMBER='(12)';
      BIDIRECTIONAL='TRUE';
      INPUT_LOAD='(-0.01,0.01)';
      OUTPUT_LOAD='(1.0,-1.0)';
    '13':
      PIN_NUMBER='(13)';
      BIDIRECTIONAL='TRUE';
      INPUT_LOAD='(-0.01,0.01)';
      OUTPUT_LOAD='(1.0,-1.0)';
    '14':
      PIN_NUMBER='(14)';
      BIDIRECTIONAL='TRUE';
      INPUT_LOAD='(-0.01,0.01)';
      OUTPUT_LOAD='(1.0,-1.0)';
  end_pin;
  body
    PART_NAME='CONN14_210HP207GBR1';
    BODY_NAME='CONN14_210HP207GBR1';
    PHYS_DES_PREFIX='J';
    CLASS='IO';
  end_body;
end_primitive;

END.
